(kicad_pcb
	(version 20241229)
	(generator "pcbnew")
	(generator_version "9.0")
	(general
		(thickness 1.6296)
		(legacy_teardrops no)
	)
	(paper "A3")
	(title_block
		(title "Thunderbolt to 10GbE adapter")
		(date "2026-04-21")
		(rev "1.1.0")
		(company "Antmicro Ltd")
		(comment 1 "www.antmicro.com")
		(comment 9 "footprints 598-601 of 703")
	)
	(layers
		(0 "F.Cu" signal)
		(4 "In1.Cu" signal)
		(6 "In2.Cu" signal)
		(8 "In3.Cu" signal)
		(10 "In4.Cu" signal)
		(12 "In5.Cu" signal)
		(14 "In6.Cu" signal)
		(2 "B.Cu" signal)
		(9 "F.Adhes" user "F.Adhesive")
		(11 "B.Adhes" user "B.Adhesive")
		(13 "F.Paste" user)
		(15 "B.Paste" user)
		(5 "F.SilkS" user "F.Silkscreen")
		(7 "B.SilkS" user "B.Silkscreen")
		(1 "F.Mask" user)
		(3 "B.Mask" user)
		(17 "Dwgs.User" user "User.Drawings")
		(19 "Cmts.User" user "User.Comments")
		(21 "Eco1.User" user "User.Eco1")
		(23 "Eco2.User" user "User.Eco2")
		(25 "Edge.Cuts" user)
		(27 "Margin" user)
		(31 "F.CrtYd" user "F.Courtyard")
		(29 "B.CrtYd" user "B.Courtyard")
		(35 "F.Fab" user)
		(33 "B.Fab" user)
	)
	(footprint "antmicro-footprints:L_0402_1005Metric"
		(layer "B.Cu")
		(at 167 137.5)
		(descr "Inductor SMD 0402")
		(tags "Inductor SMD 0402")
		(property "Reference" "L13"
			(at 3 0.5 180)
			(layer "B.SilkS")
			(effects
				(font
					(size 0.7 0.7)
					(thickness 0.15)
				)
				(justify left bottom mirror)
			)
		)
		(property "Value" "L_2n4_0.85A_0402"
			(at 0 -1.4 180)
			(layer "B.Fab")
			(effects
				(font
					(size 0.7 0.7)
					(thickness 0.15)
				)
				(justify left bottom mirror)
			)
		)
		(property "Datasheet" "https://www.murata.com/products/productdetail?partno=LQW15AN2N4B00%23"
			(at 0 0 180)
			(layer "B.Fab")
			(hide yes)
			(effects
				(font
					(size 1.27 1.27)
					(thickness 0.15)
				)
				(justify mirror)
			)
		)
		(property "Description" "Wirewound Inductor, 2.4 nH, 0.05 ohm, 15 GHz, 850 mA, 0402 [1005 Metric], LQW15AN"
			(at 0 0 180)
			(layer "B.Fab")
			(hide yes)
			(effects
				(font
					(size 1.27 1.27)
					(thickness 0.15)
				)
				(justify mirror)
			)
		)
		(property "Val" "2n4/0.85A"
			(at 0 0 0)
			(unlocked yes)
			(layer "B.Fab")
			(hide yes)
			(effects
				(font
					(size 1 1)
					(thickness 0.15)
				)
				(justify mirror)
			)
		)
		(property "Manufacturer" "Murata"
			(at 0 0 0)
			(unlocked yes)
			(layer "B.Fab")
			(hide yes)
			(effects
				(font
					(size 1 1)
					(thickness 0.15)
				)
				(justify mirror)
			)
		)
		(property "MPN" "LQW15AN2N4B00D"
			(at 0 0 0)
			(unlocked yes)
			(layer "B.Fab")
			(hide yes)
			(effects
				(font
					(size 1 1)
					(thickness 0.15)
				)
				(justify mirror)
			)
		)
		(property "ISat" "0.85 A"
			(at 0 0 0)
			(unlocked yes)
			(layer "B.Fab")
			(hide yes)
			(effects
				(font
					(size 1 1)
					(thickness 0.15)
				)
				(justify mirror)
			)
		)
		(property "IMax" "0.85 A"
			(at 0 0 0)
			(unlocked yes)
			(layer "B.Fab")
			(hide yes)
			(effects
				(font
					(size 1 1)
					(thickness 0.15)
				)
				(justify mirror)
			)
		)
		(property "Size" "1.0x0.5"
			(at 0 0 0)
			(unlocked yes)
			(layer "B.Fab")
			(hide yes)
			(effects
				(font
					(size 1 1)
					(thickness 0.15)
				)
				(justify mirror)
			)
		)
		(property "Author" "Antmicro"
			(at 0 0 0)
			(unlocked yes)
			(layer "B.Fab")
			(hide yes)
			(effects
				(font
					(size 1 1)
					(thickness 0.15)
				)
				(justify mirror)
			)
		)
		(property "License" "Apache-2.0"
			(at 0 0 0)
			(unlocked yes)
			(layer "B.Fab")
			(hide yes)
			(effects
				(font
					(size 1 1)
					(thickness 0.15)
				)
				(justify mirror)
			)
		)
		(sheetname "/2xRJ45/")
		(sheetfile "2xrj45.kicad_sch")
		(attr smd)
		(fp_rect
			(start -0.925 0.47)
			(end 0.925 -0.47)
			(stroke
				(width 0.05)
				(type default)
			)
			(fill no)
			(layer "B.CrtYd")
		)
		(fp_rect
			(start -0.499 0.249)
			(end 0.499 -0.249)
			(stroke
				(width 0.15)
				(type solid)
			)
			(fill no)
			(layer "B.Fab")
		)
		(fp_text user "${REFERENCE}"
			(at -0.932 -3.168 180)
			(layer "B.Fab")
			(effects
				(font
					(size 0.7 0.7)
					(thickness 0.15)
				)
				(justify left bottom mirror)
			)
		)
		(fp_text user "License: Apache-2.0"
			(at -0.932 -5.17 180)
			(layer "B.Fab")
			(effects
				(font
					(size 0.7 0.7)
					(thickness 0.15)
				)
				(justify left bottom mirror)
			)
		)
		(fp_text user "Author: Antmicro"
			(at -0.932 -4.17 180)
			(layer "B.Fab")
			(effects
				(font
					(size 0.7 0.7)
					(thickness 0.15)
				)
				(justify left bottom mirror)
			)
		)
		(pad "1" smd roundrect
			(at -0.48 0)
			(size 0.59 0.64)
			(layers "B.Cu" "B.Mask" "B.Paste")
			(roundrect_rratio 0.25)
			(net 135 "+1V88_CT")
			(pintype "passive")
		)
		(pad "2" smd roundrect
			(at 0.48 0)
			(size 0.59 0.64)
			(layers "B.Cu" "B.Mask" "B.Paste")
			(roundrect_rratio 0.25)
			(net 134 "/2xRJ45/P1_CT")
			(pintype "passive")
		)
	)
	(footprint "antmicro-footprints:C_0402_1005Metric"
		(layer "B.Cu")
		(at 124.3 150.6 180)
		(descr "Capacitor SMD 0402")
		(tags "capacitor SMD 0402")
		(property "Reference" "C2"
			(at -0.7 -1.65 0)
			(layer "B.SilkS")
			(effects
				(font
					(size 0.7 0.7)
					(thickness 0.15)
				)
				(justify left bottom mirror)
			)
		)
		(property "Value" "C_100n_0402"
			(at -1.022927 -2.155213 0)
			(layer "B.Fab")
			(effects
				(font
					(size 0.7 0.7)
					(thickness 0.15)
				)
				(justify left bottom mirror)
			)
		)
		(property "Datasheet" "https://www.murata.com/products/productdetail?partno=GRM155R61H104KE14%23"
			(at 0 0 0)
			(layer "B.Fab")
			(hide yes)
			(effects
				(font
					(size 1.27 1.27)
					(thickness 0.15)
				)
				(justify mirror)
			)
		)
		(property "Description" "SMD Multilayer Ceramic Capacitor, 0.1 µF, 50 V, 0402 [1005 Metric], ± 10%, X5R, GRM Series"
			(at 0 0 0)
			(layer "B.Fab")
			(hide yes)
			(effects
				(font
					(size 1.27 1.27)
					(thickness 0.15)
				)
				(justify mirror)
			)
		)
		(property "MPN" "GRM155R61H104KE14D"
			(at 0 0 180)
			(unlocked yes)
			(layer "B.Fab")
			(hide yes)
			(effects
				(font
					(size 1 1)
					(thickness 0.15)
				)
				(justify mirror)
			)
		)
		(property "Manufacturer" "Murata"
			(at 0 0 180)
			(unlocked yes)
			(layer "B.Fab")
			(hide yes)
			(effects
				(font
					(size 1 1)
					(thickness 0.15)
				)
				(justify mirror)
			)
		)
		(property "License" "Apache-2.0"
			(at 0 0 180)
			(unlocked yes)
			(layer "B.Fab")
			(hide yes)
			(effects
				(font
					(size 1 1)
					(thickness 0.15)
				)
				(justify mirror)
			)
		)
		(property "Val" "100n"
			(at 0 0 180)
			(unlocked yes)
			(layer "B.Fab")
			(hide yes)
			(effects
				(font
					(size 1 1)
					(thickness 0.15)
				)
				(justify mirror)
			)
		)
		(property "Voltage" "50V"
			(at 0 0 180)
			(unlocked yes)
			(layer "B.Fab")
			(hide yes)
			(effects
				(font
					(size 1 1)
					(thickness 0.15)
				)
				(justify mirror)
			)
		)
		(property "Dielectric" "X5R"
			(at 0 0 180)
			(unlocked yes)
			(layer "B.Fab")
			(hide yes)
			(effects
				(font
					(size 1 1)
					(thickness 0.15)
				)
				(justify mirror)
			)
		)
		(property "Author" "Antmicro"
			(at 0 0 180)
			(unlocked yes)
			(layer "B.Fab")
			(hide yes)
			(effects
				(font
					(size 1 1)
					(thickness 0.15)
				)
				(justify mirror)
			)
		)
		(sheetname "/USB-C connector/")
		(sheetfile "USB-C_connector.kicad_sch")
		(attr smd)
		(fp_rect
			(start -0.925 0.47)
			(end 0.925 -0.47)
			(stroke
				(width 0.05)
				(type default)
			)
			(fill no)
			(layer "B.CrtYd")
		)
		(fp_line
			(start 0.504 0.25)
			(end 0.504 -0.248)
			(stroke
				(width 0.15)
				(type solid)
			)
			(layer "B.Fab")
		)
		(fp_line
			(start 0.504 -0.248)
			(end -0.494 -0.248)
			(stroke
				(width 0.15)
				(type solid)
			)
			(layer "B.Fab")
		)
		(fp_line
			(start -0.494 0.25)
			(end 0.504 0.25)
			(stroke
				(width 0.15)
				(type solid)
			)
			(layer "B.Fab")
		)
		(fp_line
			(start -0.494 -0.248)
			(end -0.494 0.25)
			(stroke
				(width 0.15)
				(type solid)
			)
			(layer "B.Fab")
		)
		(fp_text user "License: Apache-2.0"
			(at -0.939 -5.799 0)
			(layer "B.Fab")
			(effects
				(font
					(size 0.7 0.7)
					(thickness 0.15)
				)
				(justify left bottom mirror)
			)
		)
		(fp_text user "${REFERENCE}"
			(at -0.939 -4.599 0)
			(layer "B.Fab")
			(effects
				(font
					(size 0.7 0.7)
					(thickness 0.15)
				)
				(justify left bottom mirror)
			)
		)
		(fp_text user "Author: Antmicro"
			(at -0.939 -3.399 0)
			(layer "B.Fab")
			(effects
				(font
					(size 0.7 0.7)
					(thickness 0.15)
				)
				(justify left bottom mirror)
			)
		)
		(pad "1" smd roundrect
			(at -0.48 0 180)
			(size 0.59 0.64)
			(layers "B.Cu" "B.Mask" "B.Paste")
			(roundrect_rratio 0.25)
			(net 23 "GND")
			(pintype "passive")
		)
		(pad "2" smd roundrect
			(at 0.48 0 180)
			(size 0.59 0.64)
			(layers "B.Cu" "B.Mask" "B.Paste")
			(roundrect_rratio 0.25)
			(net 215 "/USB-C connector/VBUS")
			(pintype "passive")
		)
	)
	(footprint "antmicro-footprints:FB_0603_1608Metric"
		(layer "B.Cu")
		(at 156.481866 93.385117 90)
		(property "Reference" "FB3"
			(at -9.914883 18.318134 270)
			(layer "B.SilkS")
			(effects
				(font
					(size 0.7 0.7)
					(thickness 0.15)
				)
				(justify mirror)
			)
		)
		(property "Value" "FB_470Z_1A_Murata-BLM18PG_0603"
			(at 0 -1.5 270)
			(layer "B.Fab")
			(effects
				(font
					(size 0.7 0.7)
					(thickness 0.15)
				)
				(justify left bottom mirror)
			)
		)
		(property "Datasheet" "https://www.murata.com/en-us/products/productdata/8796738650142/ENFA0003.pdf"
			(at 0 0 270)
			(layer "B.Fab")
			(hide yes)
			(effects
				(font
					(size 1.27 1.27)
					(thickness 0.15)
				)
				(justify mirror)
			)
		)
		(property "Description" "Ferrite Bead, 0603 [1608 Metric], 470 ohm, 1 A, BLM18P, 0.2 ohm, ± 25%, DC power line"
			(at 0 0 270)
			(layer "B.Fab")
			(hide yes)
			(effects
				(font
					(size 1.27 1.27)
					(thickness 0.15)
				)
				(justify mirror)
			)
		)
		(property "Val" "470Z/1A"
			(at 0 0 90)
			(unlocked yes)
			(layer "B.Fab")
			(hide yes)
			(effects
				(font
					(size 1 1)
					(thickness 0.15)
				)
				(justify mirror)
			)
		)
		(property "MPN" "BLM18PG471SN1D"
			(at 0 0 90)
			(unlocked yes)
			(layer "B.Fab")
			(hide yes)
			(effects
				(font
					(size 1 1)
					(thickness 0.15)
				)
				(justify mirror)
			)
		)
		(property "Manufacturer" "Murata"
			(at 0 0 90)
			(unlocked yes)
			(layer "B.Fab")
			(hide yes)
			(effects
				(font
					(size 1 1)
					(thickness 0.15)
				)
				(justify mirror)
			)
		)
		(property "Current" ""
			(at 0 0 90)
			(unlocked yes)
			(layer "B.Fab")
			(hide yes)
			(effects
				(font
					(size 1 1)
					(thickness 0.15)
				)
				(justify mirror)
			)
		)
		(property "Author" "Antmicro"
			(at 0 0 90)
			(unlocked yes)
			(layer "B.Fab")
			(hide yes)
			(effects
				(font
					(size 1 1)
					(thickness 0.15)
				)
				(justify mirror)
			)
		)
		(property "License" "Apache-2.0"
			(at 0 0 90)
			(unlocked yes)
			(layer "B.Fab")
			(hide yes)
			(effects
				(font
					(size 1 1)
					(thickness 0.15)
				)
				(justify mirror)
			)
		)
		(sheetname "/X710-AT2 power/")
		(sheetfile "x710-at2-power.kicad_sch")
		(attr smd)
		(fp_line
			(start -0.15 -0.4)
			(end 0.15 -0.4)
			(stroke
				(width 0.15)
				(type solid)
			)
			(layer "B.SilkS")
		)
		(fp_line
			(start -0.15 0.4)
			(end 0.15 0.4)
			(stroke
				(width 0.15)
				(type solid)
			)
			(layer "B.SilkS")
		)
		(fp_rect
			(start -1.25 0.65)
			(end 1.25 -0.65)
			(stroke
				(width 0.05)
				(type solid)
			)
			(fill no)
			(layer "B.CrtYd")
		)
		(fp_line
			(start 0.8 -0.406)
			(end -0.803 -0.406)
			(stroke
				(width 0.15)
				(type solid)
			)
			(layer "B.Fab")
		)
		(fp_line
			(start -0.803 -0.406)
			(end -0.803 0.408)
			(stroke
				(width 0.15)
				(type solid)
			)
			(layer "B.Fab")
		)
		(fp_line
			(start 0.8 0.408)
			(end 0.8 -0.406)
			(stroke
				(width 0.15)
				(type solid)
			)
			(layer "B.Fab")
		)
		(fp_line
			(start 0.8 0.408)
			(end -0.803 0.408)
			(stroke
				(width 0.15)
				(type solid)
			)
			(layer "B.Fab")
		)
		(fp_text user "Author: Antmicro"
			(at -1.653 -3.162 270)
			(layer "B.Fab")
			(effects
				(font
					(size 0.7 0.7)
					(thickness 0.15)
				)
				(justify left bottom mirror)
			)
		)
		(fp_text user "License: Apache-2.0"
			(at -1.653 -5.9 270)
			(layer "B.Fab")
			(effects
				(font
					(size 0.7 0.7)
					(thickness 0.15)
				)
				(justify left bottom mirror)
			)
		)
		(fp_text user "${REFERENCE}"
			(at -1.653 -4.6 270)
			(layer "B.Fab")
			(effects
				(font
					(size 0.7 0.7)
					(thickness 0.15)
				)
				(justify left bottom mirror)
			)
		)
		(pad "1" smd roundrect
			(at -0.7 0 90)
			(size 0.8 1)
			(layers "B.Cu" "B.Mask" "B.Paste")
			(roundrect_rratio 0.2)
			(net 136 "+1V0")
			(pintype "passive")
		)
		(pad "2" smd roundrect
			(at 0.7 0 90)
			(size 0.8 1)
			(layers "B.Cu" "B.Mask" "B.Paste")
			(roundrect_rratio 0.2)
			(net 22 "PLL_VDD")
			(pintype "passive")
		)
	)
	(footprint "antmicro-footprints:R_0402_1005Metric"
		(layer "B.Cu")
		(at 135.600001 126.604998)
		(descr "Resistor SMD 0402")
		(tags "resistor SMD 0402")
		(property "Reference" "R59"
			(at 19.525001 -7.450001 180)
			(layer "B.SilkS")
			(effects
				(font
					(size 0.7 0.7)
					(thickness 0.15)
				)
				(justify mirror)
			)
		)
		(property "Value" "R_1M_0402"
			(at -1.011843 -1.772047 180)
			(layer "B.Fab")
			(effects
				(font
					(size 0.7 0.7)
					(thickness 0.15)
				)
				(justify left bottom mirror)
			)
		)
		(property "Datasheet" "https://www.bourns.com/docs/product-datasheets/cr.pdf"
			(at 0 0 180)
			(layer "B.Fab")
			(hide yes)
			(effects
				(font
					(size 1.27 1.27)
					(thickness 0.15)
				)
				(justify mirror)
			)
		)
		(property "Description" "SMD Chip Resistor, 1 Mohm, ± 1%, 62.5 mW, 0402 [1005 Metric], Thick Film, General Purpose"
			(at 0 0 180)
			(layer "B.Fab")
			(hide yes)
			(effects
				(font
					(size 1.27 1.27)
					(thickness 0.15)
				)
				(justify mirror)
			)
		)
		(property "MPN" "CR0402-FX-1004GLF"
			(at 0 0 0)
			(unlocked yes)
			(layer "B.Fab")
			(hide yes)
			(effects
				(font
					(size 1 1)
					(thickness 0.15)
				)
				(justify mirror)
			)
		)
		(property "Manufacturer" "Bourns"
			(at 0 0 0)
			(unlocked yes)
			(layer "B.Fab")
			(hide yes)
			(effects
				(font
					(size 1 1)
					(thickness 0.15)
				)
				(justify mirror)
			)
		)
		(property "License" "Apache-2.0"
			(at 0 0 0)
			(unlocked yes)
			(layer "B.Fab")
			(hide yes)
			(effects
				(font
					(size 1 1)
					(thickness 0.15)
				)
				(justify mirror)
			)
		)
		(property "Val" "1M"
			(at 0 0 0)
			(unlocked yes)
			(layer "B.Fab")
			(hide yes)
			(effects
				(font
					(size 1 1)
					(thickness 0.15)
				)
				(justify mirror)
			)
		)
		(property "Tolerance" "1%"
			(at 0 0 0)
			(unlocked yes)
			(layer "B.Fab")
			(hide yes)
			(effects
				(font
					(size 1 1)
					(thickness 0.15)
				)
				(justify mirror)
			)
		)
		(property "Author" "Antmicro"
			(at 0 0 0)
			(unlocked yes)
			(layer "B.Fab")
			(hide yes)
			(effects
				(font
					(size 1 1)
					(thickness 0.15)
				)
				(justify mirror)
			)
		)
		(sheetname "/TB Controller/")
		(sheetfile "tb.kicad_sch")
		(attr smd)
		(fp_rect
			(start -0.925 0.47)
			(end 0.925 -0.47)
			(stroke
				(width 0.05)
				(type default)
			)
			(fill no)
			(layer "B.CrtYd")
		)
		(fp_rect
			(start -0.5 0.25)
			(end 0.5 -0.25)
			(stroke
				(width 0.15)
				(type solid)
			)
			(fill no)
			(layer "B.Fab")
		)
		(fp_text user "License: Apache-2.0"
			(at -0.95 -5.169 180)
			(layer "B.Fab")
			(effects
				(font
					(size 0.7 0.7)
					(thickness 0.15)
				)
				(justify left bottom mirror)
			)
		)
		(fp_text user "${REFERENCE}"
			(at -0.95 -3.168 180)
			(layer "B.Fab")
			(effects
				(font
					(size 0.7 0.7)
					(thickness 0.15)
				)
				(justify left bottom mirror)
			)
		)
		(fp_text user "Author: Antmicro"
			(at -0.95 -4.169 180)
			(layer "B.Fab")
			(effects
				(font
					(size 0.7 0.7)
					(thickness 0.15)
				)
				(justify left bottom mirror)
			)
		)
		(pad "1" smd roundrect
			(at -0.48 0)
			(size 0.59 0.64)
			(layers "B.Cu" "B.Mask" "B.Paste")
			(roundrect_rratio 0.25)
			(net 232 "Net-(U4E-PB_LSRX)")
			(pintype "passive")
		)
		(pad "2" smd roundrect
			(at 0.48 0)
			(size 0.59 0.64)
			(layers "B.Cu" "B.Mask" "B.Paste")
			(roundrect_rratio 0.25)
			(net 23 "GND")
			(pintype "passive")
		)
	)
)
